(kicad_pcb
	(version 20260206)
	(generator "pcbnew")
	(generator_version "10.0")
	(general
		(thickness 1.6)
		(legacy_teardrops no)
	)
	(paper "A4")
	(title_block
		(title "panther-plus-userver — 13130-1b_20150205.brd")
		(comment 1 "Honey Badger (Wiwynn) / footprints 58-65 of 1509")
	)
	(layers
		(0 "F.Cu" signal "TOP")
		(4 "In1.Cu" signal "L2")
		(6 "In2.Cu" signal "L3")
		(8 "In3.Cu" signal "L4")
		(10 "In4.Cu" signal "L5")
		(12 "In5.Cu" signal "L6")
		(14 "In6.Cu" signal "L7")
		(16 "In7.Cu" signal "L8")
		(18 "In8.Cu" signal "L9")
		(20 "In9.Cu" signal "L10")
		(22 "In10.Cu" signal "L11")
		(2 "B.Cu" signal "BOTTOM")
		(9 "F.Adhes" user "F.Adhesive")
		(11 "B.Adhes" user "B.Adhesive")
		(13 "F.Paste" user "Package Geometry/Pastemask Top")
		(15 "B.Paste" user "Package Geometry/Pastemask Bottom")
		(5 "F.SilkS" user "Ref Des/Silkscreen Top")
		(7 "B.SilkS" user "Ref Des/Silkscreen Bottom")
		(1 "F.Mask" user "Board Geometry/Soldermask Top")
		(3 "B.Mask" user "Board Geometry/Soldermask Bottom")
		(17 "Dwgs.User" user "User.Drawings")
		(19 "Cmts.User" user "User.Comments")
		(21 "Eco1.User" user "User.Eco1")
		(23 "Eco2.User" user "User.Eco2")
		(25 "Edge.Cuts" user "Board Geometry/Outline")
		(27 "Margin" user)
		(31 "F.CrtYd" user "Package Geometry/Place Bound Top")
		(29 "B.CrtYd" user "Package Geometry/Place Bound Bottom")
		(35 "F.Fab" user "Ref Des/Assembly Top")
		(33 "B.Fab" user "Ref Des/Assembly Bottom")
	)
	(footprint ""
		(layer "F.Cu")
		(at 47.2948 -54.6481 -90)
		(property "Reference" "R113"
			(at 0 0 270)
			(layer "F.SilkS")
			(hide yes)
			(effects
				(font
					(size 1.27 1.27)
				)
			)
		)
		(property "Value" "2D2R3J-2-GP"
			(at -0.0254 -2.0193 270)
			(unlocked yes)
			(layer "F.Fab")
			(hide yes)
			(effects
				(font
					(size 1.016 1.016)
					(thickness 0.1524)
				)
			)
		)
		(property "Device Type" "R603H22"
			(at -0.0254 -3.5433 270)
			(unlocked yes)
			(layer "F.Fab")
			(hide yes)
			(effects
				(font
					(size 1.016 1.016)
					(thickness 0.1524)
				)
			)
		)
		(duplicate_pad_numbers_are_jumpers no)
		(fp_line
			(start -0.2032 0)
			(end -0.4191 0)
			(stroke
				(width 0.2032)
				(type default)
			)
			(layer "F.SilkS")
		)
		(fp_line
			(start 0.4318 0)
			(end 0.2032 0)
			(stroke
				(width 0.2032)
				(type default)
			)
			(layer "F.SilkS")
		)
		(fp_rect
			(start -0.635 1.1811)
			(end 0.635 -1.1811)
			(stroke
				(width 0)
				(type default)
			)
			(fill no)
			(layer "F.CrtYd")
		)
		(fp_rect
			(start -0.635 1.1811)
			(end 0.635 -1.1811)
			(stroke
				(width 0)
				(type default)
			)
			(fill no)
			(layer "F.Fab")
		)
		(pad "1" smd custom
			(at 0 -0.6604 270)
			(size 0.19685 0.19685)
			(layers "F.Cu" "F.Mask" "F.Paste")
			(net "P3V3_CLK_R_VDD25")
			(options
				(clearance outline)
				(anchor circle)
			)
			(primitives
				(gr_poly
					(pts
						(arc
							(start 0.508 -0.2921)
							(mid 0.478242 -0.363942)
							(end 0.4064 -0.3937)
						)
						(arc
							(start -0.4064 -0.3937)
							(mid -0.478242 -0.363942)
							(end -0.508 -0.2921)
						)
						(arc
							(start -0.508 0.2921)
							(mid -0.478242 0.363942)
							(end -0.4064 0.3937)
						)
						(arc
							(start 0.4064 0.3937)
							(mid 0.478242 0.363942)
							(end 0.508 0.2921)
						)
					)
					(width 0)
					(fill yes)
				)
			)
		)
		(pad "2" smd custom
			(at 0 0.6604 270)
			(size 0.19685 0.19685)
			(layers "F.Cu" "F.Mask" "F.Paste")
			(net "P3V3_CLK_VDD25")
			(options
				(clearance outline)
				(anchor circle)
			)
			(primitives
				(gr_poly
					(pts
						(arc
							(start 0.508 -0.2921)
							(mid 0.478242 -0.363942)
							(end 0.4064 -0.3937)
						)
						(arc
							(start -0.4064 -0.3937)
							(mid -0.478242 -0.363942)
							(end -0.508 -0.2921)
						)
						(arc
							(start -0.508 0.2921)
							(mid -0.478242 0.363942)
							(end -0.4064 0.3937)
						)
						(arc
							(start 0.4064 0.3937)
							(mid 0.478242 0.363942)
							(end 0.508 0.2921)
						)
					)
					(width 0)
					(fill yes)
				)
			)
		)
	)
	(footprint ""
		(layer "F.Cu")
		(at 10.668 -50.4952 90)
		(property "Reference" "C64"
			(at 0 0 90)
			(layer "F.SilkS")
			(hide yes)
			(effects
				(font
					(size 1.27 1.27)
				)
			)
		)
		(property "Value" "SCD01U16V2KX-3GP"
			(at 1.1811 -2.7051 90)
			(unlocked yes)
			(layer "F.Fab")
			(hide yes)
			(effects
				(font
					(size 1.016 1.016)
					(thickness 0.1524)
				)
			)
		)
		(property "Device Type" "C402H22"
			(at 1.1811 -4.2291 90)
			(unlocked yes)
			(layer "F.Fab")
			(hide yes)
			(effects
				(font
					(size 1.016 1.016)
					(thickness 0.1524)
				)
			)
		)
		(duplicate_pad_numbers_are_jumpers no)
		(fp_rect
			(start -0.381 0.7366)
			(end 0.381 -0.7366)
			(stroke
				(width 0)
				(type default)
			)
			(fill no)
			(layer "F.CrtYd")
		)
		(fp_rect
			(start -0.381 0.7366)
			(end 0.381 -0.7366)
			(stroke
				(width 0)
				(type default)
			)
			(fill no)
			(layer "F.Fab")
		)
		(pad "1" smd custom
			(at 0 -0.4572 90)
			(size 0.1143 0.1143)
			(layers "F.Cu" "F.Mask" "F.Paste")
			(net "SATA3_TX_DP1")
			(options
				(clearance outline)
				(anchor circle)
			)
			(primitives
				(gr_poly
					(pts
						(arc
							(start -0.254 -0.1778)
							(mid -0.239121 -0.213721)
							(end -0.2032 -0.2286)
						)
						(arc
							(start 0.2032 -0.2286)
							(mid 0.239121 -0.213721)
							(end 0.254 -0.1778)
						)
						(arc
							(start 0.254 0.1778)
							(mid 0.239121 0.213721)
							(end 0.2032 0.2286)
						)
						(arc
							(start -0.2032 0.2286)
							(mid -0.239121 0.213721)
							(end -0.254 0.1778)
						)
					)
					(width 0)
					(fill yes)
				)
			)
		)
		(pad "2" smd custom
			(at 0 0.4572 90)
			(size 0.1143 0.1143)
			(layers "F.Cu" "F.Mask" "F.Paste")
			(net "P2E_CPU_NGFF_TX_DP12")
			(options
				(clearance outline)
				(anchor circle)
			)
			(primitives
				(gr_poly
					(pts
						(arc
							(start -0.254 -0.1778)
							(mid -0.239121 -0.213721)
							(end -0.2032 -0.2286)
						)
						(arc
							(start 0.2032 -0.2286)
							(mid 0.239121 -0.213721)
							(end 0.254 -0.1778)
						)
						(arc
							(start 0.254 0.1778)
							(mid 0.239121 0.213721)
							(end 0.2032 0.2286)
						)
						(arc
							(start -0.2032 0.2286)
							(mid -0.239121 0.213721)
							(end -0.254 0.1778)
						)
					)
					(width 0)
					(fill yes)
				)
			)
		)
	)
	(footprint ""
		(layer "F.Cu")
		(at 137.541 -19.177 -90)
		(property "Reference" "R57"
			(at 0 0 270)
			(layer "F.SilkS")
			(hide yes)
			(effects
				(font
					(size 1.27 1.27)
				)
			)
		)
		(property "Value" "4K7R2F-GP"
			(at 0.064008 -3.993896 270)
			(unlocked yes)
			(layer "F.Fab")
			(hide yes)
			(effects
				(font
					(size 1.016 1.016)
					(thickness 0.1524)
				)
			)
		)
		(property "Device Type" "R402H16"
			(at 0.064008 -5.517896 270)
			(unlocked yes)
			(layer "F.Fab")
			(hide yes)
			(effects
				(font
					(size 1.016 1.016)
					(thickness 0.1524)
				)
			)
		)
		(duplicate_pad_numbers_are_jumpers no)
		(fp_rect
			(start -0.381 0.8382)
			(end 0.381 -0.8382)
			(stroke
				(width 0)
				(type default)
			)
			(fill no)
			(layer "F.CrtYd")
		)
		(fp_rect
			(start -0.381 0.8382)
			(end 0.381 -0.8382)
			(stroke
				(width 0)
				(type default)
			)
			(fill no)
			(layer "F.Fab")
		)
		(pad "1" smd custom
			(at 0 -0.4318 270)
			(size 0.127 0.127)
			(layers "F.Cu" "F.Mask" "F.Paste")
			(net "P3V3_STBY")
			(options
				(clearance outline)
				(anchor circle)
			)
			(primitives
				(gr_poly
					(pts
						(arc
							(start -0.2032 -0.2794)
							(mid -0.239121 -0.264521)
							(end -0.254 -0.2286)
						)
						(arc
							(start -0.254 0.2286)
							(mid -0.239121 0.264521)
							(end -0.2032 0.2794)
						)
						(arc
							(start 0.2032 0.2794)
							(mid 0.239121 0.264521)
							(end 0.254 0.2286)
						)
						(arc
							(start 0.254 -0.2286)
							(mid 0.239121 -0.264521)
							(end 0.2032 -0.2794)
						)
					)
					(width 0)
					(fill yes)
				)
			)
		)
		(pad "2" smd custom
			(at 0 0.4318 270)
			(size 0.127 0.127)
			(layers "F.Cu" "F.Mask" "F.Paste")
			(net "HOST_R_RSTBTN#")
			(options
				(clearance outline)
				(anchor circle)
			)
			(primitives
				(gr_poly
					(pts
						(arc
							(start -0.2032 -0.2794)
							(mid -0.239121 -0.264521)
							(end -0.254 -0.2286)
						)
						(arc
							(start -0.254 0.2286)
							(mid -0.239121 0.264521)
							(end -0.2032 0.2794)
						)
						(arc
							(start 0.2032 0.2794)
							(mid 0.239121 0.264521)
							(end 0.254 0.2286)
						)
						(arc
							(start 0.254 -0.2286)
							(mid 0.239121 -0.264521)
							(end 0.2032 -0.2794)
						)
					)
					(width 0)
					(fill yes)
				)
			)
		)
	)
	(footprint ""
		(layer "F.Cu")
		(at 74.1172 -25.1206)
		(property "Reference" "R139"
			(at 0 0 0)
			(layer "F.SilkS")
			(hide yes)
			(effects
				(font
					(size 1.27 1.27)
				)
			)
		)
		(property "Value" "10KR2F-2-GP"
			(at 0.064008 -3.993896 0)
			(unlocked yes)
			(layer "F.Fab")
			(hide yes)
			(effects
				(font
					(size 1.016 1.016)
					(thickness 0.1524)
				)
			)
		)
		(property "Device Type" "R402H16"
			(at 0.064008 -5.517896 0)
			(unlocked yes)
			(layer "F.Fab")
			(hide yes)
			(effects
				(font
					(size 1.016 1.016)
					(thickness 0.1524)
				)
			)
		)
		(duplicate_pad_numbers_are_jumpers no)
		(fp_rect
			(start -0.381 0.8382)
			(end 0.381 -0.8382)
			(stroke
				(width 0)
				(type default)
			)
			(fill no)
			(layer "F.CrtYd")
		)
		(fp_rect
			(start -0.381 0.8382)
			(end 0.381 -0.8382)
			(stroke
				(width 0)
				(type default)
			)
			(fill no)
			(layer "F.Fab")
		)
		(pad "1" smd custom
			(at 0 -0.4318)
			(size 0.127 0.127)
			(layers "F.Cu" "F.Mask" "F.Paste")
			(net "P3V3_CPU")
			(options
				(clearance outline)
				(anchor circle)
			)
			(primitives
				(gr_poly
					(pts
						(arc
							(start -0.2032 -0.2794)
							(mid -0.239121 -0.264521)
							(end -0.254 -0.2286)
						)
						(arc
							(start -0.254 0.2286)
							(mid -0.239121 0.264521)
							(end -0.2032 0.2794)
						)
						(arc
							(start 0.2032 0.2794)
							(mid 0.239121 0.264521)
							(end 0.254 0.2286)
						)
						(arc
							(start 0.254 -0.2286)
							(mid 0.239121 -0.264521)
							(end 0.2032 -0.2794)
						)
					)
					(width 0)
					(fill yes)
				)
			)
		)
		(pad "2" smd custom
			(at 0 0.4318)
			(size 0.127 0.127)
			(layers "F.Cu" "F.Mask" "F.Paste")
			(net "GBE_SMBDATA")
			(options
				(clearance outline)
				(anchor circle)
			)
			(primitives
				(gr_poly
					(pts
						(arc
							(start -0.2032 -0.2794)
							(mid -0.239121 -0.264521)
							(end -0.254 -0.2286)
						)
						(arc
							(start -0.254 0.2286)
							(mid -0.239121 0.264521)
							(end -0.2032 0.2794)
						)
						(arc
							(start 0.2032 0.2794)
							(mid 0.239121 0.264521)
							(end 0.254 0.2286)
						)
						(arc
							(start 0.254 -0.2286)
							(mid 0.239121 -0.264521)
							(end 0.2032 -0.2794)
						)
					)
					(width 0)
					(fill yes)
				)
			)
		)
	)
	(footprint ""
		(layer "F.Cu")
		(at 184.912 -53.848)
		(property "Reference" "R204"
			(at 0 0 0)
			(layer "F.SilkS")
			(hide yes)
			(effects
				(font
					(size 1.27 1.27)
				)
			)
		)
		(property "Value" "100R2F-L1-GP-U"
			(at 0.064008 -3.993896 0)
			(unlocked yes)
			(layer "F.Fab")
			(hide yes)
			(effects
				(font
					(size 1.016 1.016)
					(thickness 0.1524)
				)
			)
		)
		(property "Device Type" "R402H14"
			(at 0.064008 -5.517896 0)
			(unlocked yes)
			(layer "F.Fab")
			(hide yes)
			(effects
				(font
					(size 1.016 1.016)
					(thickness 0.1524)
				)
			)
		)
		(duplicate_pad_numbers_are_jumpers no)
		(fp_rect
			(start -0.381 0.8382)
			(end 0.381 -0.8382)
			(stroke
				(width 0)
				(type default)
			)
			(fill no)
			(layer "F.CrtYd")
		)
		(fp_rect
			(start -0.381 0.8382)
			(end 0.381 -0.8382)
			(stroke
				(width 0)
				(type default)
			)
			(fill no)
			(layer "F.Fab")
		)
		(pad "1" smd custom
			(at 0 -0.4318)
			(size 0.127 0.127)
			(layers "F.Cu" "F.Mask" "F.Paste")
			(net "PV_VDDR")
			(options
				(clearance outline)
				(anchor circle)
			)
			(primitives
				(gr_poly
					(pts
						(arc
							(start -0.2032 -0.2794)
							(mid -0.239121 -0.264521)
							(end -0.254 -0.2286)
						)
						(arc
							(start -0.254 0.2286)
							(mid -0.239121 0.264521)
							(end -0.2032 0.2794)
						)
						(arc
							(start 0.2032 0.2794)
							(mid 0.239121 0.264521)
							(end 0.254 0.2286)
						)
						(arc
							(start 0.254 -0.2286)
							(mid 0.239121 -0.264521)
							(end 0.2032 -0.2794)
						)
					)
					(width 0)
					(fill yes)
				)
			)
		)
		(pad "2" smd custom
			(at 0 0.4318)
			(size 0.127 0.127)
			(layers "F.Cu" "F.Mask" "F.Paste")
			(net "PV_VDDR_VREF_A_FB")
			(options
				(clearance outline)
				(anchor circle)
			)
			(primitives
				(gr_poly
					(pts
						(arc
							(start -0.2032 -0.2794)
							(mid -0.239121 -0.264521)
							(end -0.254 -0.2286)
						)
						(arc
							(start -0.254 0.2286)
							(mid -0.239121 0.264521)
							(end -0.2032 0.2794)
						)
						(arc
							(start 0.2032 0.2794)
							(mid 0.239121 0.264521)
							(end 0.254 0.2286)
						)
						(arc
							(start 0.254 -0.2286)
							(mid 0.239121 -0.264521)
							(end 0.2032 -0.2794)
						)
					)
					(width 0)
					(fill yes)
				)
			)
		)
	)
	(footprint ""
		(layer "F.Cu")
		(at 9.4488 -46.736 90)
		(property "Reference" "R11"
			(at 0 0 90)
			(layer "F.SilkS")
			(hide yes)
			(effects
				(font
					(size 1.27 1.27)
				)
			)
		)
		(property "Value" "4K7R2F-GP"
			(at 0.064008 -3.993896 90)
			(unlocked yes)
			(layer "F.Fab")
			(hide yes)
			(effects
				(font
					(size 1.016 1.016)
					(thickness 0.1524)
				)
			)
		)
		(property "Device Type" "R402H16"
			(at 0.064008 -5.517896 90)
			(unlocked yes)
			(layer "F.Fab")
			(hide yes)
			(effects
				(font
					(size 1.016 1.016)
					(thickness 0.1524)
				)
			)
		)
		(duplicate_pad_numbers_are_jumpers no)
		(fp_rect
			(start -0.381 0.8382)
			(end 0.381 -0.8382)
			(stroke
				(width 0)
				(type default)
			)
			(fill no)
			(layer "F.CrtYd")
		)
		(fp_rect
			(start -0.381 0.8382)
			(end 0.381 -0.8382)
			(stroke
				(width 0)
				(type default)
			)
			(fill no)
			(layer "F.Fab")
		)
		(pad "1" smd custom
			(at 0 -0.4318 90)
			(size 0.127 0.127)
			(layers "F.Cu" "F.Mask" "F.Paste")
			(net "TEMP_1_A2")
			(options
				(clearance outline)
				(anchor circle)
			)
			(primitives
				(gr_poly
					(pts
						(arc
							(start -0.2032 -0.2794)
							(mid -0.239121 -0.264521)
							(end -0.254 -0.2286)
						)
						(arc
							(start -0.254 0.2286)
							(mid -0.239121 0.264521)
							(end -0.2032 0.2794)
						)
						(arc
							(start 0.2032 0.2794)
							(mid 0.239121 0.264521)
							(end 0.254 0.2286)
						)
						(arc
							(start 0.254 -0.2286)
							(mid 0.239121 -0.264521)
							(end 0.2032 -0.2794)
						)
					)
					(width 0)
					(fill yes)
				)
			)
		)
		(pad "2" smd custom
			(at 0 0.4318 90)
			(size 0.127 0.127)
			(layers "F.Cu" "F.Mask" "F.Paste")
			(net "GND")
			(options
				(clearance outline)
				(anchor circle)
			)
			(primitives
				(gr_poly
					(pts
						(arc
							(start -0.2032 -0.2794)
							(mid -0.239121 -0.264521)
							(end -0.254 -0.2286)
						)
						(arc
							(start -0.254 0.2286)
							(mid -0.239121 0.264521)
							(end -0.2032 0.2794)
						)
						(arc
							(start 0.2032 0.2794)
							(mid 0.239121 0.264521)
							(end 0.254 0.2286)
						)
						(arc
							(start 0.254 -0.2286)
							(mid 0.239121 -0.264521)
							(end 0.2032 -0.2794)
						)
					)
					(width 0)
					(fill yes)
				)
			)
		)
	)
	(footprint ""
		(layer "F.Cu")
		(at 56.261 -54.356 180)
		(property "Reference" "PR151"
			(at 0 0 180)
			(layer "F.SilkS")
			(hide yes)
			(effects
				(font
					(size 1.27 1.27)
				)
			)
		)
		(property "Value" "237KR2F-GP"
			(at 1.7907 -1.1176 180)
			(unlocked yes)
			(layer "F.Fab")
			(hide yes)
			(effects
				(font
					(size 1.016 1.016)
					(thickness 0.1524)
				)
			)
		)
		(property "Device Type" "R402H16"
			(at 1.7907 -2.6416 180)
			(unlocked yes)
			(layer "F.Fab")
			(hide yes)
			(effects
				(font
					(size 1.016 1.016)
					(thickness 0.1524)
				)
			)
		)
		(duplicate_pad_numbers_are_jumpers no)
		(fp_rect
			(start -0.381 0.8382)
			(end 0.381 -0.8382)
			(stroke
				(width 0)
				(type default)
			)
			(fill no)
			(layer "F.CrtYd")
		)
		(fp_rect
			(start -0.381 0.8382)
			(end 0.381 -0.8382)
			(stroke
				(width 0)
				(type default)
			)
			(fill no)
			(layer "F.Fab")
		)
		(pad "1" smd custom
			(at 0 -0.4318 180)
			(size 0.127 0.127)
			(layers "F.Cu" "F.Mask" "F.Paste")
			(net "VR_FB_R_P1V0_STBY")
			(options
				(clearance outline)
				(anchor circle)
			)
			(primitives
				(gr_poly
					(pts
						(arc
							(start -0.2032 -0.2794)
							(mid -0.239121 -0.264521)
							(end -0.254 -0.2286)
						)
						(arc
							(start -0.254 0.2286)
							(mid -0.239121 0.264521)
							(end -0.2032 0.2794)
						)
						(arc
							(start 0.2032 0.2794)
							(mid 0.239121 0.264521)
							(end 0.254 0.2286)
						)
						(arc
							(start 0.254 -0.2286)
							(mid 0.239121 -0.264521)
							(end 0.2032 -0.2794)
						)
					)
					(width 0)
					(fill yes)
				)
			)
		)
		(pad "2" smd custom
			(at 0 0.4318 180)
			(size 0.127 0.127)
			(layers "F.Cu" "F.Mask" "F.Paste")
			(net "VR_FB_P1V0_STBY")
			(options
				(clearance outline)
				(anchor circle)
			)
			(primitives
				(gr_poly
					(pts
						(arc
							(start -0.2032 -0.2794)
							(mid -0.239121 -0.264521)
							(end -0.254 -0.2286)
						)
						(arc
							(start -0.254 0.2286)
							(mid -0.239121 0.264521)
							(end -0.2032 0.2794)
						)
						(arc
							(start 0.2032 0.2794)
							(mid 0.239121 0.264521)
							(end 0.254 0.2286)
						)
						(arc
							(start 0.254 -0.2286)
							(mid 0.239121 -0.264521)
							(end 0.2032 -0.2794)
						)
					)
					(width 0)
					(fill yes)
				)
			)
		)
	)
	(footprint ""
		(layer "F.Cu")
		(at 182.9308 -30.4038 90)
		(property "Reference" "PC105"
			(at 0 0 90)
			(layer "F.SilkS")
			(hide yes)
			(effects
				(font
					(size 1.27 1.27)
				)
			)
		)
		(property "Value" "SC68P50V2JN-1GP"
			(at 1.8923 -1.2065 90)
			(unlocked yes)
			(layer "F.Fab")
			(hide yes)
			(effects
				(font
					(size 1.016 1.016)
					(thickness 0.1524)
				)
			)
		)
		(property "Device Type" "C402H22"
			(at 1.8923 -2.7305 90)
			(unlocked yes)
			(layer "F.Fab")
			(hide yes)
			(effects
				(font
					(size 1.016 1.016)
					(thickness 0.1524)
				)
			)
		)
		(duplicate_pad_numbers_are_jumpers no)
		(fp_rect
			(start -0.381 0.7366)
			(end 0.381 -0.7366)
			(stroke
				(width 0)
				(type default)
			)
			(fill no)
			(layer "F.CrtYd")
		)
		(fp_rect
			(start -0.381 0.7366)
			(end 0.381 -0.7366)
			(stroke
				(width 0)
				(type default)
			)
			(fill no)
			(layer "F.Fab")
		)
		(pad "1" smd custom
			(at 0 -0.4572 90)
			(size 0.1143 0.1143)
			(layers "F.Cu" "F.Mask" "F.Paste")
			(net "VR_PVDDR_A_COMP")
			(options
				(clearance outline)
				(anchor circle)
			)
			(primitives
				(gr_poly
					(pts
						(arc
							(start -0.254 -0.1778)
							(mid -0.239121 -0.213721)
							(end -0.2032 -0.2286)
						)
						(arc
							(start 0.2032 -0.2286)
							(mid 0.239121 -0.213721)
							(end 0.254 -0.1778)
						)
						(arc
							(start 0.254 0.1778)
							(mid 0.239121 0.213721)
							(end 0.2032 0.2286)
						)
						(arc
							(start -0.2032 0.2286)
							(mid -0.239121 0.213721)
							(end -0.254 0.1778)
						)
					)
					(width 0)
					(fill yes)
				)
			)
		)
		(pad "2" smd custom
			(at 0 0.4572 90)
			(size 0.1143 0.1143)
			(layers "F.Cu" "F.Mask" "F.Paste")
			(net "VR_PVDDR_A_FB")
			(options
				(clearance outline)
				(anchor circle)
			)
			(primitives
				(gr_poly
					(pts
						(arc
							(start -0.254 -0.1778)
							(mid -0.239121 -0.213721)
							(end -0.2032 -0.2286)
						)
						(arc
							(start 0.2032 -0.2286)
							(mid 0.239121 -0.213721)
							(end 0.254 -0.1778)
						)
						(arc
							(start 0.254 0.1778)
							(mid 0.239121 0.213721)
							(end 0.2032 0.2286)
						)
						(arc
							(start -0.2032 0.2286)
							(mid -0.239121 0.213721)
							(end -0.254 0.1778)
						)
					)
					(width 0)
					(fill yes)
				)
			)
		)
	)
)
